# T6G (Grand Teton) — schematic netlist excerpt (pin names and nets, part order shuffled) for the footprints in the layout excerpt that follows; sources: Cadence DE-HDL packaged netlist, KiCad conversion of 04192023_DAF0TMB3IC0_F0TG_MB_C_brd_V02_OCP.brd

R1153  Q_RES  0 5% CHIP  pkg 0402LF  page 160 : A = SMB_CPU0_CPU1_SEC_SCL_R1 ; B = SMB_CPU0_CPU1_SEC_SCL_R2
C284  Q_CAP  22UF 4V 20% X6S  pkg C0402  page 323 : A = P0V9_CPU1_RT0_2A ; B = GND

(kicad_pcb
	(version 20260206)
	(generator "pcbnew")
	(generator_version "10.0")
	(general
		(thickness 1.6)
		(legacy_teardrops no)
	)
	(paper "A4")
	(title_block
		(title "04192023_DAF0TMB3IC0_F0TG_MB_C_brd_V02_OCP.brd")
		(comment 1 "Grand Teton / footprints 7741-7742 of 8354")
	)
	(layers
		(0 "F.Cu" signal "TOP")
		(4 "In1.Cu" signal "GND")
		(6 "In2.Cu" signal "IN1")
		(8 "In3.Cu" signal "GND1")
		(10 "In4.Cu" signal "IN2")
		(12 "In5.Cu" signal "GND2")
		(14 "In6.Cu" signal "IN3")
		(16 "In7.Cu" signal "GND3")
		(18 "In8.Cu" signal "VCC")
		(20 "In9.Cu" signal "VCC1")
		(22 "In10.Cu" signal "GND4")
		(24 "In11.Cu" signal "IN4")
		(26 "In12.Cu" signal "GND5")
		(28 "In13.Cu" signal "IN5")
		(30 "In14.Cu" signal "GND6")
		(32 "In15.Cu" signal "IN6")
		(34 "In16.Cu" signal "GND7")
		(2 "B.Cu" signal "BOTTOM")
		(9 "F.Adhes" user "F.Adhesive")
		(11 "B.Adhes" user "B.Adhesive")
		(13 "F.Paste" user "Package Geometry/Pastemask Top")
		(15 "B.Paste" user "Package Geometry/Pastemask Bottom")
		(5 "F.SilkS" user "Ref Des/Silkscreen Top")
		(7 "B.SilkS" user "Ref Des/Silkscreen Bottom")
		(1 "F.Mask" user "Board Geometry/Soldermask Top")
		(3 "B.Mask" user "Board Geometry/Soldermask Bottom")
		(17 "Dwgs.User" user "User.Drawings")
		(19 "Cmts.User" user "User.Comments")
		(21 "Eco1.User" user "User.Eco1")
		(23 "Eco2.User" user "User.Eco2")
		(25 "Edge.Cuts" user "Board Geometry/Outline")
		(27 "Margin" user)
		(31 "F.CrtYd" user "Package Geometry/Place Bound Top")
		(29 "B.CrtYd" user "Package Geometry/Place Bound Bottom")
		(35 "F.Fab" user "Ref Des/Assembly Top")
		(33 "B.Fab" user "Ref Des/Assembly Bottom")
	)
	(footprint ""
		(layer "B.Cu")
		(at 62.991238 -390.560052 90)
		(property "Reference" "C284"
			(at 0 0 90)
			(layer "B.SilkS")
			(hide yes)
			(effects
				(font
					(size 1.27 1.27)
				)
				(justify mirror)
			)
		)
		(property "Value" ""
			(at 0 0 90)
			(layer "B.Fab")
			(effects
				(font
					(size 1.27 1.27)
				)
				(justify mirror)
			)
		)
		(duplicate_pad_numbers_are_jumpers no)
		(fp_line
			(start 0.7874 -0.4064)
			(end -0.7874 -0.4064)
			(stroke
				(width 0.1524)
				(type default)
			)
			(layer "B.SilkS")
		)
		(fp_line
			(start -0.7874 -0.4064)
			(end -0.7874 0.4064)
			(stroke
				(width 0.1524)
				(type default)
			)
			(layer "B.SilkS")
		)
		(fp_line
			(start 0.7874 0.4064)
			(end 0.7874 -0.4064)
			(stroke
				(width 0.1524)
				(type default)
			)
			(layer "B.SilkS")
		)
		(fp_line
			(start -0.7874 0.4064)
			(end 0.7874 0.4064)
			(stroke
				(width 0.1524)
				(type default)
			)
			(layer "B.SilkS")
		)
		(fp_line
			(start 0.67945 -0.305054)
			(end 0.12065 -0.305054)
			(stroke
				(width 0.1)
				(type default)
			)
			(layer "B.Fab")
		)
		(fp_line
			(start 0.12065 -0.305054)
			(end 0.12065 -0.2794)
			(stroke
				(width 0.1)
				(type default)
			)
			(layer "B.Fab")
		)
		(fp_line
			(start -0.12065 -0.3048)
			(end -0.67945 -0.3048)
			(stroke
				(width 0.1)
				(type default)
			)
			(layer "B.Fab")
		)
		(fp_line
			(start -0.67945 -0.3048)
			(end -0.67945 0.3048)
			(stroke
				(width 0.1)
				(type default)
			)
			(layer "B.Fab")
		)
		(fp_line
			(start 0.12065 -0.2794)
			(end -0.12065 -0.2794)
			(stroke
				(width 0.1)
				(type default)
			)
			(layer "B.Fab")
		)
		(fp_line
			(start -0.12065 -0.2794)
			(end -0.12065 -0.3048)
			(stroke
				(width 0.1)
				(type default)
			)
			(layer "B.Fab")
		)
		(fp_line
			(start 0.12065 0.2794)
			(end 0.12065 0.3048)
			(stroke
				(width 0.1)
				(type default)
			)
			(layer "B.Fab")
		)
		(fp_line
			(start -0.120396 0.2794)
			(end 0.12065 0.2794)
			(stroke
				(width 0.1)
				(type default)
			)
			(layer "B.Fab")
		)
		(fp_line
			(start 0.67945 0.3048)
			(end 0.67945 -0.305054)
			(stroke
				(width 0.1)
				(type default)
			)
			(layer "B.Fab")
		)
		(fp_line
			(start 0.12065 0.3048)
			(end 0.67945 0.3048)
			(stroke
				(width 0.1)
				(type default)
			)
			(layer "B.Fab")
		)
		(fp_line
			(start -0.120396 0.3048)
			(end -0.120396 0.2794)
			(stroke
				(width 0.1)
				(type default)
			)
			(layer "B.Fab")
		)
		(fp_line
			(start -0.67945 0.3048)
			(end -0.120396 0.3048)
			(stroke
				(width 0.1)
				(type default)
			)
			(layer "B.Fab")
		)
		(pad "1" smd circle
			(at 0.40005 0 270)
			(size 0 0)
			(layers "B.Cu" "B.Mask" "B.Paste")
			(net "P0V9_CPU1_RT0_2A")
		)
		(pad "2" smd circle
			(at -0.40005 0 270)
			(size 0 0)
			(layers "B.Cu" "B.Mask" "B.Paste")
			(net "GND")
		)
	)
	(footprint ""
		(layer "B.Cu")
		(at 242.951 -228.092 -90)
		(property "Reference" "R1153"
			(at 0 0 90)
			(layer "B.SilkS")
			(hide yes)
			(effects
				(font
					(size 1.27 1.27)
				)
				(justify mirror)
			)
		)
		(property "Value" ""
			(at 0 0 90)
			(layer "B.Fab")
			(effects
				(font
					(size 1.27 1.27)
				)
				(justify mirror)
			)
		)
		(duplicate_pad_numbers_are_jumpers no)
		(fp_line
			(start -0.7874 0.4064)
			(end 0.7874 0.4064)
			(stroke
				(width 0.1524)
				(type default)
			)
			(layer "B.SilkS")
		)
		(fp_line
			(start 0.7874 0.4064)
			(end 0.7874 -0.4064)
			(stroke
				(width 0.1524)
				(type default)
			)
			(layer "B.SilkS")
		)
		(fp_line
			(start -0.7874 -0.4064)
			(end -0.7874 0.4064)
			(stroke
				(width 0.1524)
				(type default)
			)
			(layer "B.SilkS")
		)
		(fp_line
			(start 0.7874 -0.4064)
			(end -0.7874 -0.4064)
			(stroke
				(width 0.1524)
				(type default)
			)
			(layer "B.SilkS")
		)
		(fp_line
			(start -0.67945 0.3048)
			(end -0.120396 0.3048)
			(stroke
				(width 0.1)
				(type default)
			)
			(layer "B.Fab")
		)
		(fp_line
			(start -0.120396 0.3048)
			(end -0.120396 0.2794)
			(stroke
				(width 0.1)
				(type default)
			)
			(layer "B.Fab")
		)
		(fp_line
			(start 0.12065 0.3048)
			(end 0.67945 0.3048)
			(stroke
				(width 0.1)
				(type default)
			)
			(layer "B.Fab")
		)
		(fp_line
			(start 0.67945 0.3048)
			(end 0.67945 -0.305054)
			(stroke
				(width 0.1)
				(type default)
			)
			(layer "B.Fab")
		)
		(fp_line
			(start -0.120396 0.2794)
			(end 0.12065 0.2794)
			(stroke
				(width 0.1)
				(type default)
			)
			(layer "B.Fab")
		)
		(fp_line
			(start 0.12065 0.2794)
			(end 0.12065 0.3048)
			(stroke
				(width 0.1)
				(type default)
			)
			(layer "B.Fab")
		)
		(fp_line
			(start -0.12065 -0.2794)
			(end -0.12065 -0.3048)
			(stroke
				(width 0.1)
				(type default)
			)
			(layer "B.Fab")
		)
		(fp_line
			(start 0.12065 -0.2794)
			(end -0.12065 -0.2794)
			(stroke
				(width 0.1)
				(type default)
			)
			(layer "B.Fab")
		)
		(fp_line
			(start -0.67945 -0.3048)
			(end -0.67945 0.3048)
			(stroke
				(width 0.1)
				(type default)
			)
			(layer "B.Fab")
		)
		(fp_line
			(start -0.12065 -0.3048)
			(end -0.67945 -0.3048)
			(stroke
				(width 0.1)
				(type default)
			)
			(layer "B.Fab")
		)
		(fp_line
			(start 0.12065 -0.305054)
			(end 0.12065 -0.2794)
			(stroke
				(width 0.1)
				(type default)
			)
			(layer "B.Fab")
		)
		(fp_line
			(start 0.67945 -0.305054)
			(end 0.12065 -0.305054)
			(stroke
				(width 0.1)
				(type default)
			)
			(layer "B.Fab")
		)
		(pad "1" smd circle
			(at 0.40005 0 90)
			(size 0 0)
			(layers "B.Cu" "B.Mask" "B.Paste")
			(net "SMB_CPU0_CPU1_SEC_SCL_R1")
		)
		(pad "2" smd circle
			(at -0.40005 0 90)
			(size 0 0)
			(layers "B.Cu" "B.Mask" "B.Paste")
			(net "SMB_CPU0_CPU1_SEC_SCL_R2")
		)
	)
)
